(kicad_pcb
	(version 20260206)
	(generator "pcbnew")
	(generator_version "10.0")
	(general
		(thickness 1.6)
		(legacy_teardrops no)
	)
	(paper "A4")
	(title_block
		(title "Bryce Canyon_SCC_16316-1_OCP.brd")
		(comment 1 "Bryce Canyon / footprints 1050-1056 of 1561")
	)
	(layers
		(0 "F.Cu" signal "TOP")
		(4 "In1.Cu" signal "L2GND")
		(6 "In2.Cu" signal "L3")
		(8 "In3.Cu" signal "L4VCC")
		(10 "In4.Cu" signal "L5VCC")
		(12 "In5.Cu" signal "L6")
		(14 "In6.Cu" signal "L7GND")
		(2 "B.Cu" signal "BOTTOM")
		(9 "F.Adhes" user "F.Adhesive")
		(11 "B.Adhes" user "B.Adhesive")
		(13 "F.Paste" user "Package Geometry/Pastemask Top")
		(15 "B.Paste" user "Package Geometry/Pastemask Bottom")
		(5 "F.SilkS" user "Ref Des/Silkscreen Top")
		(7 "B.SilkS" user "Ref Des/Silkscreen Bottom")
		(1 "F.Mask" user "Board Geometry/Soldermask Top")
		(3 "B.Mask" user "Board Geometry/Soldermask Bottom")
		(17 "Dwgs.User" user "User.Drawings")
		(19 "Cmts.User" user "User.Comments")
		(21 "Eco1.User" user "User.Eco1")
		(23 "Eco2.User" user "User.Eco2")
		(25 "Edge.Cuts" user "Board Geometry/Outline")
		(27 "Margin" user)
		(31 "F.CrtYd" user "Package Geometry/Place Bound Top")
		(29 "B.CrtYd" user "Package Geometry/Place Bound Bottom")
		(35 "F.Fab" user "Ref Des/Assembly Top")
		(33 "B.Fab" user "Ref Des/Assembly Bottom")
	)
	(footprint ""
		(layer "B.Cu")
		(at 114.945414 -89.31656 -90)
		(property "Reference" "R45"
			(at 0 0 90)
			(layer "B.SilkS")
			(hide yes)
			(effects
				(font
					(size 1.27 1.27)
				)
				(justify mirror)
			)
		)
		(property "Value" "4K7R2F-GP"
			(at -0.064008 -3.993896 270)
			(unlocked yes)
			(layer "B.Fab")
			(hide yes)
			(effects
				(font
					(size 1.016 1.016)
					(thickness 0.1524)
				)
				(justify mirror)
			)
		)
		(property "Device Type" "R402H16"
			(at -0.064008 -5.517896 270)
			(unlocked yes)
			(layer "B.Fab")
			(hide yes)
			(effects
				(font
					(size 1.016 1.016)
					(thickness 0.1524)
				)
				(justify mirror)
			)
		)
		(duplicate_pad_numbers_are_jumpers no)
		(fp_line
			(start -0.508 -0.9398)
			(end 0.508 -0.9398)
			(stroke
				(width 0.1524)
				(type default)
			)
			(layer "B.SilkS")
		)
		(fp_line
			(start 0.508 -0.9398)
			(end 0.508 0.9398)
			(stroke
				(width 0.1524)
				(type default)
			)
			(layer "B.SilkS")
		)
		(fp_rect
			(start 0.508 0.9398)
			(end -0.508 -0.9398)
			(stroke
				(width 0)
				(type default)
			)
			(fill no)
			(layer "B.CrtYd")
		)
		(fp_rect
			(start 0.508 0.9398)
			(end -0.508 -0.9398)
			(stroke
				(width 0)
				(type default)
			)
			(fill no)
			(layer "B.Fab")
		)
		(pad "1" smd custom
			(at 0 -0.4445 90)
			(size 0.1397 0.1397)
			(layers "B.Cu" "B.Mask" "B.Paste")
			(net "EXP_GPIO14")
			(options
				(clearance outline)
				(anchor circle)
			)
			(primitives
				(gr_poly
					(pts
						(arc
							(start -0.1778 0.2794)
							(mid -0.249642 0.249642)
							(end -0.2794 0.1778)
						)
						(arc
							(start -0.2794 -0.1778)
							(mid -0.249642 -0.249642)
							(end -0.1778 -0.2794)
						)
						(arc
							(start 0.1778 -0.2794)
							(mid 0.249642 -0.249642)
							(end 0.2794 -0.1778)
						)
						(arc
							(start 0.2794 0.1778)
							(mid 0.249642 0.249642)
							(end 0.1778 0.2794)
						)
					)
					(width 0)
					(fill yes)
				)
			)
		)
		(pad "2" smd custom
			(at 0 0.4445 90)
			(size 0.1397 0.1397)
			(layers "B.Cu" "B.Mask" "B.Paste")
			(net "GND")
			(options
				(clearance outline)
				(anchor circle)
			)
			(primitives
				(gr_poly
					(pts
						(arc
							(start -0.1778 0.2794)
							(mid -0.249642 0.249642)
							(end -0.2794 0.1778)
						)
						(arc
							(start -0.2794 -0.1778)
							(mid -0.249642 -0.249642)
							(end -0.1778 -0.2794)
						)
						(arc
							(start 0.1778 -0.2794)
							(mid 0.249642 -0.249642)
							(end 0.2794 -0.1778)
						)
						(arc
							(start 0.2794 0.1778)
							(mid 0.249642 0.249642)
							(end 0.1778 0.2794)
						)
					)
					(width 0)
					(fill yes)
				)
			)
		)
	)
	(footprint ""
		(layer "B.Cu")
		(at 169.4942 -38.8366 180)
		(property "Reference" "C401"
			(at 0 0 0)
			(layer "B.SilkS")
			(hide yes)
			(effects
				(font
					(size 1.27 1.27)
				)
				(justify mirror)
			)
		)
		(property "Value" "SCD1U16V2KX-3GP"
			(at -1.1811 -2.7051 180)
			(unlocked yes)
			(layer "B.Fab")
			(hide yes)
			(effects
				(font
					(size 1.016 1.016)
					(thickness 0.1524)
				)
				(justify mirror)
			)
		)
		(property "Device Type" "C402H22"
			(at -1.1811 -4.2291 180)
			(unlocked yes)
			(layer "B.Fab")
			(hide yes)
			(effects
				(font
					(size 1.016 1.016)
					(thickness 0.1524)
				)
				(justify mirror)
			)
		)
		(duplicate_pad_numbers_are_jumpers no)
		(fp_rect
			(start 0.4318 0.9525)
			(end -0.4318 -0.9525)
			(stroke
				(width 0)
				(type default)
			)
			(fill no)
			(layer "B.CrtYd")
		)
		(fp_rect
			(start 0.4318 0.9525)
			(end -0.4318 -0.9525)
			(stroke
				(width 0)
				(type default)
			)
			(fill no)
			(layer "B.Fab")
		)
		(pad "1" smd custom
			(at 0 -0.4445)
			(size 0.1524 0.1524)
			(layers "B.Cu" "B.Mask" "B.Paste")
			(net "SAS0_AVDD")
			(options
				(clearance outline)
				(anchor circle)
			)
			(primitives
				(gr_poly
					(pts
						(arc
							(start 0.3048 0.2032)
							(mid 0.275042 0.275042)
							(end 0.2032 0.3048)
						)
						(arc
							(start -0.2032 0.3048)
							(mid -0.275042 0.275042)
							(end -0.3048 0.2032)
						)
						(arc
							(start -0.3048 -0.2032)
							(mid -0.275042 -0.275042)
							(end -0.2032 -0.3048)
						)
						(arc
							(start 0.2032 -0.3048)
							(mid 0.275042 -0.275042)
							(end 0.3048 -0.2032)
						)
					)
					(width 0)
					(fill yes)
				)
			)
		)
		(pad "2" smd custom
			(at 0 0.4445)
			(size 0.1524 0.1524)
			(layers "B.Cu" "B.Mask" "B.Paste")
			(net "GND")
			(options
				(clearance outline)
				(anchor circle)
			)
			(primitives
				(gr_poly
					(pts
						(arc
							(start 0.3048 0.2032)
							(mid 0.275042 0.275042)
							(end 0.2032 0.3048)
						)
						(arc
							(start -0.2032 0.3048)
							(mid -0.275042 0.275042)
							(end -0.3048 0.2032)
						)
						(arc
							(start -0.3048 -0.2032)
							(mid -0.275042 -0.275042)
							(end -0.2032 -0.3048)
						)
						(arc
							(start 0.2032 -0.3048)
							(mid 0.275042 -0.275042)
							(end 0.3048 -0.2032)
						)
					)
					(width 0)
					(fill yes)
				)
			)
		)
	)
	(footprint ""
		(layer "B.Cu")
		(at 112.6998 -71.9074)
		(property "Reference" "C150"
			(at 0 0 0)
			(layer "B.SilkS")
			(hide yes)
			(effects
				(font
					(size 1.27 1.27)
				)
				(justify mirror)
			)
		)
		(property "Value" "SCD1U6D3V1KX-GP"
			(at 2.8321 -1.7399 0)
			(unlocked yes)
			(layer "B.Fab")
			(hide yes)
			(effects
				(font
					(size 1.016 1.016)
					(thickness 0.1524)
				)
				(justify mirror)
			)
		)
		(property "Device Type" "C0201H13"
			(at 2.8321 -3.2639 0)
			(unlocked yes)
			(layer "B.Fab")
			(hide yes)
			(effects
				(font
					(size 1.016 1.016)
					(thickness 0.1524)
				)
				(justify mirror)
			)
		)
		(duplicate_pad_numbers_are_jumpers no)
		(fp_rect
			(start 0.2794 0.6477)
			(end -0.2794 -0.6477)
			(stroke
				(width 0)
				(type default)
			)
			(fill no)
			(layer "B.CrtYd")
		)
		(fp_rect
			(start 0.2794 0.6477)
			(end -0.2794 -0.6477)
			(stroke
				(width 0)
				(type default)
			)
			(fill no)
			(layer "B.Fab")
		)
		(pad "1" smd custom
			(at 0 -0.2794 180)
			(size 0.0762 0.0762)
			(layers "B.Cu" "B.Mask" "B.Paste")
			(net "P1V8_E")
			(options
				(clearance outline)
				(anchor circle)
			)
			(primitives
				(gr_poly
					(pts
						(arc
							(start 0.1524 0.127)
							(mid 0.137521 0.162921)
							(end 0.1016 0.1778)
						)
						(arc
							(start -0.1016 0.1778)
							(mid -0.137521 0.162921)
							(end -0.1524 0.127)
						)
						(arc
							(start -0.1524 -0.127)
							(mid -0.137521 -0.162921)
							(end -0.1016 -0.1778)
						)
						(arc
							(start 0.1016 -0.1778)
							(mid 0.137521 -0.162921)
							(end 0.1524 -0.127)
						)
					)
					(width 0)
					(fill yes)
				)
			)
		)
		(pad "2" smd custom
			(at 0 0.2794 180)
			(size 0.0762 0.0762)
			(layers "B.Cu" "B.Mask" "B.Paste")
			(net "GND")
			(options
				(clearance outline)
				(anchor circle)
			)
			(primitives
				(gr_poly
					(pts
						(arc
							(start 0.1524 0.127)
							(mid 0.137521 0.162921)
							(end 0.1016 0.1778)
						)
						(arc
							(start -0.1016 0.1778)
							(mid -0.137521 0.162921)
							(end -0.1524 0.127)
						)
						(arc
							(start -0.1524 -0.127)
							(mid -0.137521 -0.162921)
							(end -0.1016 -0.1778)
						)
						(arc
							(start 0.1016 -0.1778)
							(mid 0.137521 -0.162921)
							(end 0.1524 -0.127)
						)
					)
					(width 0)
					(fill yes)
				)
			)
		)
	)
	(footprint ""
		(layer "B.Cu")
		(at 169.171874 -96.109282 180)
		(property "Reference" "R484"
			(at 0 0 0)
			(layer "B.SilkS")
			(hide yes)
			(effects
				(font
					(size 1.27 1.27)
				)
				(justify mirror)
			)
		)
		(property "Value" "10KR2F-2-GP"
			(at -0.064008 -3.993896 180)
			(unlocked yes)
			(layer "B.Fab")
			(hide yes)
			(effects
				(font
					(size 1.016 1.016)
					(thickness 0.1524)
				)
				(justify mirror)
			)
		)
		(property "Device Type" "R402H16"
			(at -0.064008 -5.517896 180)
			(unlocked yes)
			(layer "B.Fab")
			(hide yes)
			(effects
				(font
					(size 1.016 1.016)
					(thickness 0.1524)
				)
				(justify mirror)
			)
		)
		(duplicate_pad_numbers_are_jumpers no)
		(fp_line
			(start 0.508 -0.9398)
			(end 0.508 0.9398)
			(stroke
				(width 0.1524)
				(type default)
			)
			(layer "B.SilkS")
		)
		(fp_line
			(start -0.508 -0.9398)
			(end 0.508 -0.9398)
			(stroke
				(width 0.1524)
				(type default)
			)
			(layer "B.SilkS")
		)
		(fp_rect
			(start 0.508 0.9398)
			(end -0.508 -0.9398)
			(stroke
				(width 0)
				(type default)
			)
			(fill no)
			(layer "B.CrtYd")
		)
		(fp_rect
			(start 0.508 0.9398)
			(end -0.508 -0.9398)
			(stroke
				(width 0)
				(type default)
			)
			(fill no)
			(layer "B.Fab")
		)
		(pad "1" smd custom
			(at 0 -0.4445)
			(size 0.1397 0.1397)
			(layers "B.Cu" "B.Mask" "B.Paste")
			(net "AGND_P0V975")
			(options
				(clearance outline)
				(anchor circle)
			)
			(primitives
				(gr_poly
					(pts
						(arc
							(start -0.1778 0.2794)
							(mid -0.249642 0.249642)
							(end -0.2794 0.1778)
						)
						(arc
							(start -0.2794 -0.1778)
							(mid -0.249642 -0.249642)
							(end -0.1778 -0.2794)
						)
						(arc
							(start 0.1778 -0.2794)
							(mid 0.249642 -0.249642)
							(end 0.2794 -0.1778)
						)
						(arc
							(start 0.2794 0.1778)
							(mid 0.249642 0.249642)
							(end 0.1778 0.2794)
						)
					)
					(width 0)
					(fill yes)
				)
			)
		)
		(pad "2" smd custom
			(at 0 0.4445)
			(size 0.1397 0.1397)
			(layers "B.Cu" "B.Mask" "B.Paste")
			(net "VT235_BIAS")
			(options
				(clearance outline)
				(anchor circle)
			)
			(primitives
				(gr_poly
					(pts
						(arc
							(start -0.1778 0.2794)
							(mid -0.249642 0.249642)
							(end -0.2794 0.1778)
						)
						(arc
							(start -0.2794 -0.1778)
							(mid -0.249642 -0.249642)
							(end -0.1778 -0.2794)
						)
						(arc
							(start 0.1778 -0.2794)
							(mid 0.249642 -0.249642)
							(end 0.2794 -0.1778)
						)
						(arc
							(start 0.2794 0.1778)
							(mid 0.249642 0.249642)
							(end 0.1778 0.2794)
						)
					)
					(width 0)
					(fill yes)
				)
			)
		)
	)
	(footprint ""
		(layer "B.Cu")
		(at 100.457 -61.4934)
		(property "Reference" "C139"
			(at 0 0 0)
			(layer "B.SilkS")
			(hide yes)
			(effects
				(font
					(size 1.27 1.27)
				)
				(justify mirror)
			)
		)
		(property "Value" "SCD1U6D3V1KX-GP"
			(at 2.8321 -1.7399 0)
			(unlocked yes)
			(layer "B.Fab")
			(hide yes)
			(effects
				(font
					(size 1.016 1.016)
					(thickness 0.1524)
				)
				(justify mirror)
			)
		)
		(property "Device Type" "C0201H13"
			(at 2.8321 -3.2639 0)
			(unlocked yes)
			(layer "B.Fab")
			(hide yes)
			(effects
				(font
					(size 1.016 1.016)
					(thickness 0.1524)
				)
				(justify mirror)
			)
		)
		(duplicate_pad_numbers_are_jumpers no)
		(fp_rect
			(start 0.2794 0.6477)
			(end -0.2794 -0.6477)
			(stroke
				(width 0)
				(type default)
			)
			(fill no)
			(layer "B.CrtYd")
		)
		(fp_rect
			(start 0.2794 0.6477)
			(end -0.2794 -0.6477)
			(stroke
				(width 0)
				(type default)
			)
			(fill no)
			(layer "B.Fab")
		)
		(pad "1" smd custom
			(at 0 -0.2794 180)
			(size 0.0762 0.0762)
			(layers "B.Cu" "B.Mask" "B.Paste")
			(net "P1V8_E")
			(options
				(clearance outline)
				(anchor circle)
			)
			(primitives
				(gr_poly
					(pts
						(arc
							(start 0.1524 0.127)
							(mid 0.137521 0.162921)
							(end 0.1016 0.1778)
						)
						(arc
							(start -0.1016 0.1778)
							(mid -0.137521 0.162921)
							(end -0.1524 0.127)
						)
						(arc
							(start -0.1524 -0.127)
							(mid -0.137521 -0.162921)
							(end -0.1016 -0.1778)
						)
						(arc
							(start 0.1016 -0.1778)
							(mid 0.137521 -0.162921)
							(end 0.1524 -0.127)
						)
					)
					(width 0)
					(fill yes)
				)
			)
		)
		(pad "2" smd custom
			(at 0 0.2794 180)
			(size 0.0762 0.0762)
			(layers "B.Cu" "B.Mask" "B.Paste")
			(net "GND")
			(options
				(clearance outline)
				(anchor circle)
			)
			(primitives
				(gr_poly
					(pts
						(arc
							(start 0.1524 0.127)
							(mid 0.137521 0.162921)
							(end 0.1016 0.1778)
						)
						(arc
							(start -0.1016 0.1778)
							(mid -0.137521 0.162921)
							(end -0.1524 0.127)
						)
						(arc
							(start -0.1524 -0.127)
							(mid -0.137521 -0.162921)
							(end -0.1016 -0.1778)
						)
						(arc
							(start 0.1016 -0.1778)
							(mid 0.137521 -0.162921)
							(end 0.1524 -0.127)
						)
					)
					(width 0)
					(fill yes)
				)
			)
		)
	)
	(footprint ""
		(layer "B.Cu")
		(at 115.4557 -66.3575)
		(property "Reference" "C172"
			(at 0 0 0)
			(layer "B.SilkS")
			(hide yes)
			(effects
				(font
					(size 1.27 1.27)
				)
				(justify mirror)
			)
		)
		(property "Value" "SCD1U6D3V1KX-GP"
			(at 2.8321 -1.7399 0)
			(unlocked yes)
			(layer "B.Fab")
			(hide yes)
			(effects
				(font
					(size 1.016 1.016)
					(thickness 0.1524)
				)
				(justify mirror)
			)
		)
		(property "Device Type" "C0201H13"
			(at 2.8321 -3.2639 0)
			(unlocked yes)
			(layer "B.Fab")
			(hide yes)
			(effects
				(font
					(size 1.016 1.016)
					(thickness 0.1524)
				)
				(justify mirror)
			)
		)
		(duplicate_pad_numbers_are_jumpers no)
		(fp_rect
			(start 0.2794 0.6477)
			(end -0.2794 -0.6477)
			(stroke
				(width 0)
				(type default)
			)
			(fill no)
			(layer "B.CrtYd")
		)
		(fp_rect
			(start 0.2794 0.6477)
			(end -0.2794 -0.6477)
			(stroke
				(width 0)
				(type default)
			)
			(fill no)
			(layer "B.Fab")
		)
		(pad "1" smd custom
			(at 0 -0.2794 180)
			(size 0.0762 0.0762)
			(layers "B.Cu" "B.Mask" "B.Paste")
			(net "P0V9")
			(options
				(clearance outline)
				(anchor circle)
			)
			(primitives
				(gr_poly
					(pts
						(arc
							(start 0.1524 0.127)
							(mid 0.137521 0.162921)
							(end 0.1016 0.1778)
						)
						(arc
							(start -0.1016 0.1778)
							(mid -0.137521 0.162921)
							(end -0.1524 0.127)
						)
						(arc
							(start -0.1524 -0.127)
							(mid -0.137521 -0.162921)
							(end -0.1016 -0.1778)
						)
						(arc
							(start 0.1016 -0.1778)
							(mid 0.137521 -0.162921)
							(end 0.1524 -0.127)
						)
					)
					(width 0)
					(fill yes)
				)
			)
		)
		(pad "2" smd custom
			(at 0 0.2794 180)
			(size 0.0762 0.0762)
			(layers "B.Cu" "B.Mask" "B.Paste")
			(net "GND")
			(options
				(clearance outline)
				(anchor circle)
			)
			(primitives
				(gr_poly
					(pts
						(arc
							(start 0.1524 0.127)
							(mid 0.137521 0.162921)
							(end 0.1016 0.1778)
						)
						(arc
							(start -0.1016 0.1778)
							(mid -0.137521 0.162921)
							(end -0.1524 0.127)
						)
						(arc
							(start -0.1524 -0.127)
							(mid -0.137521 -0.162921)
							(end -0.1016 -0.1778)
						)
						(arc
							(start 0.1016 -0.1778)
							(mid 0.137521 -0.162921)
							(end 0.1524 -0.127)
						)
					)
					(width 0)
					(fill yes)
				)
			)
		)
	)
	(footprint ""
		(layer "B.Cu")
		(at 122.5804 -72.4408 -90)
		(property "Reference" "C287"
			(at 0 0 90)
			(layer "B.SilkS")
			(hide yes)
			(effects
				(font
					(size 1.27 1.27)
				)
				(justify mirror)
			)
		)
		(property "Value" "SC1U6D3V1MX-GP"
			(at -1.9177 2.0193 270)
			(unlocked yes)
			(layer "B.Fab")
			(hide yes)
			(effects
				(font
					(size 1.016 1.016)
					(thickness 0.1524)
				)
				(justify mirror)
			)
		)
		(property "Device Type" "C0201H14"
			(at -1.9177 0.4953 270)
			(unlocked yes)
			(layer "B.Fab")
			(hide yes)
			(effects
				(font
					(size 1.016 1.016)
					(thickness 0.1524)
				)
				(justify mirror)
			)
		)
		(duplicate_pad_numbers_are_jumpers no)
		(fp_rect
			(start 0.1524 0.3048)
			(end -0.1524 -0.3048)
			(stroke
				(width 0)
				(type default)
			)
			(fill no)
			(layer "B.CrtYd")
		)
		(fp_poly
			(pts
				(xy 0.2794 0.6477) (xy 0.2794 -0.6477) (xy -0.2794 -0.6477) (xy -0.2794 -0.1905) (xy -0.1524 -0.1905)
				(xy -0.1524 -0.3048) (xy 0.1524 -0.3048) (xy 0.1524 0.3048) (xy -0.1524 0.3048) (xy -0.1524 -0.1778)
				(xy -0.2794 -0.1778) (xy -0.2794 0.6477)
			)
			(stroke
				(width 0)
				(type default)
			)
			(fill no)
			(layer "B.CrtYd")
		)
		(fp_rect
			(start 0.2794 0.6477)
			(end -0.2794 -0.6477)
			(stroke
				(width 0)
				(type default)
			)
			(fill no)
			(layer "B.Fab")
		)
		(pad "1" smd custom
			(at 0 -0.2794 90)
			(size 0.0762 0.0762)
			(layers "B.Cu" "B.Mask" "B.Paste")
			(net "GB_VDDA")
			(options
				(clearance outline)
				(anchor circle)
			)
			(primitives
				(gr_poly
					(pts
						(arc
							(start 0.1524 0.127)
							(mid 0.137521 0.162921)
							(end 0.1016 0.1778)
						)
						(arc
							(start -0.1016 0.1778)
							(mid -0.137521 0.162921)
							(end -0.1524 0.127)
						)
						(arc
							(start -0.1524 -0.127)
							(mid -0.137521 -0.162921)
							(end -0.1016 -0.1778)
						)
						(arc
							(start 0.1016 -0.1778)
							(mid 0.137521 -0.162921)
							(end 0.1524 -0.127)
						)
					)
					(width 0)
					(fill yes)
				)
			)
		)
		(pad "2" smd custom
			(at 0 0.2794 90)
			(size 0.0762 0.0762)
			(layers "B.Cu" "B.Mask" "B.Paste")
			(net "GND")
			(options
				(clearance outline)
				(anchor circle)
			)
			(primitives
				(gr_poly
					(pts
						(arc
							(start 0.1524 0.127)
							(mid 0.137521 0.162921)
							(end 0.1016 0.1778)
						)
						(arc
							(start -0.1016 0.1778)
							(mid -0.137521 0.162921)
							(end -0.1524 0.127)
						)
						(arc
							(start -0.1524 -0.127)
							(mid -0.137521 -0.162921)
							(end -0.1016 -0.1778)
						)
						(arc
							(start 0.1016 -0.1778)
							(mid 0.137521 -0.162921)
							(end 0.1524 -0.127)
						)
					)
					(width 0)
					(fill yes)
				)
			)
		)
	)
)
